# S9S_MB_2U (Grand Teton) — schematic netlist excerpt (pin names and nets, part order shuffled) for the footprints in the layout excerpt that follows; sources: Cadence DE-HDL packaged netlist, KiCad conversion of 03242023_DA0F0TMBIJ0_F0T_Motherboard_J_brd_V01_OCP.brd

C2326  Q_CAP  12PF 50V 5% EMPTY  pkg C0402  page 196 : A = USB_HUB_2_XTAL_IN ; B = GND
R4807  Q_RES  0 5% EMPTY  pkg 0402LF  page 244 : A = PWRGD_DSW_PWROK_R1 ; B = PWRGD_DSW_PWROK_R2

(kicad_pcb
	(version 20260206)
	(generator "pcbnew")
	(generator_version "10.0")
	(general
		(thickness 1.6)
		(legacy_teardrops no)
	)
	(paper "A4")
	(title_block
		(title "03242023_DA0F0TMBIJ0_F0T_Motherboard_J_brd_V01_OCP.brd")
		(comment 1 "Grand Teton / footprints 3918-3919 of 6105")
	)
	(layers
		(0 "F.Cu" signal "TOP")
		(4 "In1.Cu" signal "GND")
		(6 "In2.Cu" signal "IN1")
		(8 "In3.Cu" signal "GND1")
		(10 "In4.Cu" signal "IN2")
		(12 "In5.Cu" signal "GND2")
		(14 "In6.Cu" signal "IN3")
		(16 "In7.Cu" signal "GND3")
		(18 "In8.Cu" signal "VCC")
		(20 "In9.Cu" signal "VCC1")
		(22 "In10.Cu" signal "GND4")
		(24 "In11.Cu" signal "IN4")
		(26 "In12.Cu" signal "GND5")
		(28 "In13.Cu" signal "IN5")
		(30 "In14.Cu" signal "GND6")
		(32 "In15.Cu" signal "IN6")
		(34 "In16.Cu" signal "GND7")
		(2 "B.Cu" signal "BOTTOM")
		(9 "F.Adhes" user "F.Adhesive")
		(11 "B.Adhes" user "B.Adhesive")
		(13 "F.Paste" user "Package Geometry/Pastemask Top")
		(15 "B.Paste" user "Package Geometry/Pastemask Bottom")
		(5 "F.SilkS" user "Ref Des/Silkscreen Top")
		(7 "B.SilkS" user "Ref Des/Silkscreen Bottom")
		(1 "F.Mask" user "Board Geometry/Soldermask Top")
		(3 "B.Mask" user "Board Geometry/Soldermask Bottom")
		(17 "Dwgs.User" user "User.Drawings")
		(19 "Cmts.User" user "User.Comments")
		(21 "Eco1.User" user "User.Eco1")
		(23 "Eco2.User" user "User.Eco2")
		(25 "Edge.Cuts" user "Board Geometry/Outline")
		(27 "Margin" user)
		(31 "F.CrtYd" user "Package Geometry/Place Bound Top")
		(29 "B.CrtYd" user "Package Geometry/Place Bound Bottom")
		(35 "F.Fab" user "Ref Des/Assembly Top")
		(33 "B.Fab" user "Ref Des/Assembly Bottom")
	)
	(footprint ""
		(layer "F.Cu")
		(at 152.075896 -38.575234 90)
		(property "Reference" "C2326"
			(at 0 0 90)
			(layer "F.SilkS")
			(hide yes)
			(effects
				(font
					(size 1.27 1.27)
				)
			)
		)
		(property "Value" ""
			(at 0 0 90)
			(layer "F.Fab")
			(effects
				(font
					(size 1.27 1.27)
				)
			)
		)
		(duplicate_pad_numbers_are_jumpers no)
		(fp_line
			(start 0.7874 -0.4064)
			(end 0.7874 0.4064)
			(stroke
				(width 0.1524)
				(type default)
			)
			(layer "F.SilkS")
		)
		(fp_line
			(start -0.7874 -0.4064)
			(end 0.7874 -0.4064)
			(stroke
				(width 0.1524)
				(type default)
			)
			(layer "F.SilkS")
		)
		(fp_line
			(start 0.7874 0.4064)
			(end -0.7874 0.4064)
			(stroke
				(width 0.1524)
				(type default)
			)
			(layer "F.SilkS")
		)
		(fp_line
			(start -0.7874 0.4064)
			(end -0.7874 -0.4064)
			(stroke
				(width 0.1524)
				(type default)
			)
			(layer "F.SilkS")
		)
		(fp_line
			(start -0.12065 -0.305054)
			(end -0.12065 -0.2794)
			(stroke
				(width 0.1)
				(type default)
			)
			(layer "F.Fab")
		)
		(fp_line
			(start -0.67945 -0.305054)
			(end -0.12065 -0.305054)
			(stroke
				(width 0.1)
				(type default)
			)
			(layer "F.Fab")
		)
		(fp_line
			(start 0.67945 -0.3048)
			(end 0.67945 0.3048)
			(stroke
				(width 0.1)
				(type default)
			)
			(layer "F.Fab")
		)
		(fp_line
			(start 0.12065 -0.3048)
			(end 0.67945 -0.3048)
			(stroke
				(width 0.1)
				(type default)
			)
			(layer "F.Fab")
		)
		(fp_line
			(start 0.12065 -0.2794)
			(end 0.12065 -0.3048)
			(stroke
				(width 0.1)
				(type default)
			)
			(layer "F.Fab")
		)
		(fp_line
			(start -0.12065 -0.2794)
			(end 0.12065 -0.2794)
			(stroke
				(width 0.1)
				(type default)
			)
			(layer "F.Fab")
		)
		(fp_line
			(start 0.120396 0.2794)
			(end -0.12065 0.2794)
			(stroke
				(width 0.1)
				(type default)
			)
			(layer "F.Fab")
		)
		(fp_line
			(start -0.12065 0.2794)
			(end -0.12065 0.3048)
			(stroke
				(width 0.1)
				(type default)
			)
			(layer "F.Fab")
		)
		(fp_line
			(start 0.67945 0.3048)
			(end 0.120396 0.3048)
			(stroke
				(width 0.1)
				(type default)
			)
			(layer "F.Fab")
		)
		(fp_line
			(start 0.120396 0.3048)
			(end 0.120396 0.2794)
			(stroke
				(width 0.1)
				(type default)
			)
			(layer "F.Fab")
		)
		(fp_line
			(start -0.12065 0.3048)
			(end -0.67945 0.3048)
			(stroke
				(width 0.1)
				(type default)
			)
			(layer "F.Fab")
		)
		(fp_line
			(start -0.67945 0.3048)
			(end -0.67945 -0.305054)
			(stroke
				(width 0.1)
				(type default)
			)
			(layer "F.Fab")
		)
		(pad "1" smd circle
			(at -0.40005 0 90)
			(size 0 0)
			(layers "F.Cu" "F.Mask" "F.Paste")
			(net "USB_HUB_2_XTAL_IN")
		)
		(pad "2" smd circle
			(at 0.40005 0 90)
			(size 0 0)
			(layers "F.Cu" "F.Mask" "F.Paste")
			(net "GND")
		)
	)
	(footprint ""
		(layer "F.Cu")
		(at 218.08948 -125.8062 180)
		(property "Reference" "R4807"
			(at 0 0 180)
			(layer "F.SilkS")
			(hide yes)
			(effects
				(font
					(size 1.27 1.27)
				)
			)
		)
		(property "Value" ""
			(at 0 0 180)
			(layer "F.Fab")
			(effects
				(font
					(size 1.27 1.27)
				)
			)
		)
		(duplicate_pad_numbers_are_jumpers no)
		(fp_line
			(start 0.7874 0.4064)
			(end -0.7874 0.4064)
			(stroke
				(width 0.1524)
				(type default)
			)
			(layer "F.SilkS")
		)
		(fp_line
			(start 0.7874 -0.4064)
			(end 0.7874 0.4064)
			(stroke
				(width 0.1524)
				(type default)
			)
			(layer "F.SilkS")
		)
		(fp_line
			(start -0.7874 0.4064)
			(end -0.7874 -0.4064)
			(stroke
				(width 0.1524)
				(type default)
			)
			(layer "F.SilkS")
		)
		(fp_line
			(start -0.7874 -0.4064)
			(end 0.7874 -0.4064)
			(stroke
				(width 0.1524)
				(type default)
			)
			(layer "F.SilkS")
		)
		(fp_line
			(start 0.67945 0.3048)
			(end 0.120396 0.3048)
			(stroke
				(width 0.1)
				(type default)
			)
			(layer "F.Fab")
		)
		(fp_line
			(start 0.67945 -0.3048)
			(end 0.67945 0.3048)
			(stroke
				(width 0.1)
				(type default)
			)
			(layer "F.Fab")
		)
		(fp_line
			(start 0.12065 -0.2794)
			(end 0.12065 -0.3048)
			(stroke
				(width 0.1)
				(type default)
			)
			(layer "F.Fab")
		)
		(fp_line
			(start 0.12065 -0.3048)
			(end 0.67945 -0.3048)
			(stroke
				(width 0.1)
				(type default)
			)
			(layer "F.Fab")
		)
		(fp_line
			(start 0.120396 0.3048)
			(end 0.120396 0.2794)
			(stroke
				(width 0.1)
				(type default)
			)
			(layer "F.Fab")
		)
		(fp_line
			(start 0.120396 0.2794)
			(end -0.12065 0.2794)
			(stroke
				(width 0.1)
				(type default)
			)
			(layer "F.Fab")
		)
		(fp_line
			(start -0.12065 0.3048)
			(end -0.67945 0.3048)
			(stroke
				(width 0.1)
				(type default)
			)
			(layer "F.Fab")
		)
		(fp_line
			(start -0.12065 0.2794)
			(end -0.12065 0.3048)
			(stroke
				(width 0.1)
				(type default)
			)
			(layer "F.Fab")
		)
		(fp_line
			(start -0.12065 -0.2794)
			(end 0.12065 -0.2794)
			(stroke
				(width 0.1)
				(type default)
			)
			(layer "F.Fab")
		)
		(fp_line
			(start -0.12065 -0.305054)
			(end -0.12065 -0.2794)
			(stroke
				(width 0.1)
				(type default)
			)
			(layer "F.Fab")
		)
		(fp_line
			(start -0.67945 0.3048)
			(end -0.67945 -0.305054)
			(stroke
				(width 0.1)
				(type default)
			)
			(layer "F.Fab")
		)
		(fp_line
			(start -0.67945 -0.305054)
			(end -0.12065 -0.305054)
			(stroke
				(width 0.1)
				(type default)
			)
			(layer "F.Fab")
		)
		(pad "1" smd circle
			(at -0.40005 0 180)
			(size 0 0)
			(layers "F.Cu" "F.Mask" "F.Paste")
			(net "PWRGD_DSW_PWROK_R1")
		)
		(pad "2" smd circle
			(at 0.40005 0 180)
			(size 0 0)
			(layers "F.Cu" "F.Mask" "F.Paste")
			(net "PWRGD_DSW_PWROK_R2")
		)
	)
)
